(kicad_pcb
	(version 20260206)
	(generator "pcbnew")
	(generator_version "10.0")
	(general
		(thickness 1.6)
		(legacy_teardrops no)
	)
	(paper "A4")
	(title_block
		(title "01162023_DA0F0TEBIF0_F0T_Expander_BD_F_brd_V02_OCP.brd")
		(comment 1 "Grand Teton / footprints 3659-3666 of 9728")
	)
	(layers
		(0 "F.Cu" signal "TOP")
		(4 "In1.Cu" signal "GND")
		(6 "In2.Cu" signal "VCC")
		(8 "In3.Cu" signal "VCC1")
		(10 "In4.Cu" signal "GND1")
		(12 "In5.Cu" signal "IN1")
		(14 "In6.Cu" signal "GND2")
		(16 "In7.Cu" signal "IN2")
		(18 "In8.Cu" signal "GND3")
		(20 "In9.Cu" signal "IN3")
		(22 "In10.Cu" signal "GND4")
		(24 "In11.Cu" signal "IN4")
		(26 "In12.Cu" signal "GND5")
		(28 "In13.Cu" signal "IN5")
		(30 "In14.Cu" signal "GND6")
		(32 "In15.Cu" signal "IN6")
		(34 "In16.Cu" signal "GND7")
		(2 "B.Cu" signal "BOTTOM")
		(9 "F.Adhes" user "F.Adhesive")
		(11 "B.Adhes" user "B.Adhesive")
		(13 "F.Paste" user "Package Geometry/Pastemask Top")
		(15 "B.Paste" user "Package Geometry/Pastemask Bottom")
		(5 "F.SilkS" user "Ref Des/Silkscreen Top")
		(7 "B.SilkS" user "Ref Des/Silkscreen Bottom")
		(1 "F.Mask" user "Board Geometry/Soldermask Top")
		(3 "B.Mask" user "Board Geometry/Soldermask Bottom")
		(17 "Dwgs.User" user "User.Drawings")
		(19 "Cmts.User" user "User.Comments")
		(21 "Eco1.User" user "User.Eco1")
		(23 "Eco2.User" user "User.Eco2")
		(25 "Edge.Cuts" user "Board Geometry/Outline")
		(27 "Margin" user)
		(31 "F.CrtYd" user "Package Geometry/Place Bound Top")
		(29 "B.CrtYd" user "Package Geometry/Place Bound Bottom")
		(35 "F.Fab" user "Ref Des/Assembly Top")
		(33 "B.Fab" user "Ref Des/Assembly Bottom")
	)
	(footprint ""
		(layer "F.Cu")
		(at 277.457916 -72.766682 90)
		(property "Reference" "PC862"
			(at 0 0 90)
			(layer "F.SilkS")
			(hide yes)
			(effects
				(font
					(size 1.27 1.27)
				)
			)
		)
		(property "Value" ""
			(at 0 0 90)
			(layer "F.Fab")
			(effects
				(font
					(size 1.27 1.27)
				)
			)
		)
		(duplicate_pad_numbers_are_jumpers no)
		(fp_line
			(start 0.7874 -0.4064)
			(end 0.7874 0.4064)
			(stroke
				(width 0.1524)
				(type default)
			)
			(layer "F.SilkS")
		)
		(fp_line
			(start -0.7874 -0.4064)
			(end 0.7874 -0.4064)
			(stroke
				(width 0.1524)
				(type default)
			)
			(layer "F.SilkS")
		)
		(fp_line
			(start 0.7874 0.4064)
			(end -0.7874 0.4064)
			(stroke
				(width 0.1524)
				(type default)
			)
			(layer "F.SilkS")
		)
		(fp_line
			(start -0.7874 0.4064)
			(end -0.7874 -0.4064)
			(stroke
				(width 0.1524)
				(type default)
			)
			(layer "F.SilkS")
		)
		(fp_line
			(start -0.12065 -0.305054)
			(end -0.12065 -0.2794)
			(stroke
				(width 0.1)
				(type default)
			)
			(layer "F.Fab")
		)
		(fp_line
			(start -0.67945 -0.305054)
			(end -0.12065 -0.305054)
			(stroke
				(width 0.1)
				(type default)
			)
			(layer "F.Fab")
		)
		(fp_line
			(start 0.67945 -0.3048)
			(end 0.67945 0.3048)
			(stroke
				(width 0.1)
				(type default)
			)
			(layer "F.Fab")
		)
		(fp_line
			(start 0.12065 -0.3048)
			(end 0.67945 -0.3048)
			(stroke
				(width 0.1)
				(type default)
			)
			(layer "F.Fab")
		)
		(fp_line
			(start 0.12065 -0.2794)
			(end 0.12065 -0.3048)
			(stroke
				(width 0.1)
				(type default)
			)
			(layer "F.Fab")
		)
		(fp_line
			(start -0.12065 -0.2794)
			(end 0.12065 -0.2794)
			(stroke
				(width 0.1)
				(type default)
			)
			(layer "F.Fab")
		)
		(fp_line
			(start 0.120396 0.2794)
			(end -0.12065 0.2794)
			(stroke
				(width 0.1)
				(type default)
			)
			(layer "F.Fab")
		)
		(fp_line
			(start -0.12065 0.2794)
			(end -0.12065 0.3048)
			(stroke
				(width 0.1)
				(type default)
			)
			(layer "F.Fab")
		)
		(fp_line
			(start 0.67945 0.3048)
			(end 0.120396 0.3048)
			(stroke
				(width 0.1)
				(type default)
			)
			(layer "F.Fab")
		)
		(fp_line
			(start 0.120396 0.3048)
			(end 0.120396 0.2794)
			(stroke
				(width 0.1)
				(type default)
			)
			(layer "F.Fab")
		)
		(fp_line
			(start -0.12065 0.3048)
			(end -0.67945 0.3048)
			(stroke
				(width 0.1)
				(type default)
			)
			(layer "F.Fab")
		)
		(fp_line
			(start -0.67945 0.3048)
			(end -0.67945 -0.305054)
			(stroke
				(width 0.1)
				(type default)
			)
			(layer "F.Fab")
		)
		(pad "1" smd circle
			(at -0.40005 0 90)
			(size 0 0)
			(layers "F.Cu" "F.Mask" "F.Paste")
			(net "P12V_SSD9_CO_MODE")
		)
		(pad "2" smd circle
			(at 0.40005 0 90)
			(size 0 0)
			(layers "F.Cu" "F.Mask" "F.Paste")
			(net "GND")
		)
	)
	(footprint ""
		(layer "F.Cu")
		(at 239.754918 -317.573914 180)
		(property "Reference" "PC1009"
			(at 0 0 180)
			(layer "F.SilkS")
			(hide yes)
			(effects
				(font
					(size 1.27 1.27)
				)
			)
		)
		(property "Value" ""
			(at 0 0 180)
			(layer "F.Fab")
			(effects
				(font
					(size 1.27 1.27)
				)
			)
		)
		(duplicate_pad_numbers_are_jumpers no)
		(fp_line
			(start 1.524 0.762)
			(end -1.524 0.762)
			(stroke
				(width 0.1524)
				(type default)
			)
			(layer "F.SilkS")
		)
		(fp_line
			(start 1.524 -0.762)
			(end 1.524 0.762)
			(stroke
				(width 0.1524)
				(type default)
			)
			(layer "F.SilkS")
		)
		(fp_line
			(start -1.524 0.762)
			(end -1.524 -0.762)
			(stroke
				(width 0.1524)
				(type default)
			)
			(layer "F.SilkS")
		)
		(fp_line
			(start -1.524 -0.762)
			(end 1.524 -0.762)
			(stroke
				(width 0.1524)
				(type default)
			)
			(layer "F.SilkS")
		)
		(fp_line
			(start 1.1049 0.724916)
			(end 1.1049 -0.724916)
			(stroke
				(width 0.1)
				(type default)
			)
			(layer "F.Fab")
		)
		(fp_line
			(start 1.1049 -0.724916)
			(end -1.1049 -0.724916)
			(stroke
				(width 0.1)
				(type default)
			)
			(layer "F.Fab")
		)
		(fp_line
			(start -1.1049 0.724916)
			(end 1.1049 0.724916)
			(stroke
				(width 0.1)
				(type default)
			)
			(layer "F.Fab")
		)
		(fp_line
			(start -1.1049 -0.724916)
			(end -1.1049 0.724916)
			(stroke
				(width 0.1)
				(type default)
			)
			(layer "F.Fab")
		)
		(pad "1" smd rect
			(at -0.889 0)
			(size 1.016 1.27)
			(layers "F.Cu" "F.Mask" "F.Paste")
			(net "SW_P12V_P1V25_PEX2_FLT")
		)
		(pad "2" smd rect
			(at 0.889 0)
			(size 1.016 1.27)
			(layers "F.Cu" "F.Mask" "F.Paste")
			(net "GND")
		)
	)
	(footprint ""
		(layer "F.Cu")
		(at 70.72249 -44.341542 90)
		(property "Reference" "R536"
			(at 0 0 90)
			(layer "F.SilkS")
			(hide yes)
			(effects
				(font
					(size 1.27 1.27)
				)
			)
		)
		(property "Value" ""
			(at 0 0 90)
			(layer "F.Fab")
			(effects
				(font
					(size 1.27 1.27)
				)
			)
		)
		(duplicate_pad_numbers_are_jumpers no)
		(fp_line
			(start 0.7874 -0.4064)
			(end 0.7874 0.4064)
			(stroke
				(width 0.1524)
				(type default)
			)
			(layer "F.SilkS")
		)
		(fp_line
			(start -0.7874 -0.4064)
			(end 0.7874 -0.4064)
			(stroke
				(width 0.1524)
				(type default)
			)
			(layer "F.SilkS")
		)
		(fp_line
			(start 0.7874 0.4064)
			(end -0.7874 0.4064)
			(stroke
				(width 0.1524)
				(type default)
			)
			(layer "F.SilkS")
		)
		(fp_line
			(start -0.7874 0.4064)
			(end -0.7874 -0.4064)
			(stroke
				(width 0.1524)
				(type default)
			)
			(layer "F.SilkS")
		)
		(fp_line
			(start -0.12065 -0.305054)
			(end -0.12065 -0.2794)
			(stroke
				(width 0.1)
				(type default)
			)
			(layer "F.Fab")
		)
		(fp_line
			(start -0.67945 -0.305054)
			(end -0.12065 -0.305054)
			(stroke
				(width 0.1)
				(type default)
			)
			(layer "F.Fab")
		)
		(fp_line
			(start 0.67945 -0.3048)
			(end 0.67945 0.3048)
			(stroke
				(width 0.1)
				(type default)
			)
			(layer "F.Fab")
		)
		(fp_line
			(start 0.12065 -0.3048)
			(end 0.67945 -0.3048)
			(stroke
				(width 0.1)
				(type default)
			)
			(layer "F.Fab")
		)
		(fp_line
			(start 0.12065 -0.2794)
			(end 0.12065 -0.3048)
			(stroke
				(width 0.1)
				(type default)
			)
			(layer "F.Fab")
		)
		(fp_line
			(start -0.12065 -0.2794)
			(end 0.12065 -0.2794)
			(stroke
				(width 0.1)
				(type default)
			)
			(layer "F.Fab")
		)
		(fp_line
			(start 0.120396 0.2794)
			(end -0.12065 0.2794)
			(stroke
				(width 0.1)
				(type default)
			)
			(layer "F.Fab")
		)
		(fp_line
			(start -0.12065 0.2794)
			(end -0.12065 0.3048)
			(stroke
				(width 0.1)
				(type default)
			)
			(layer "F.Fab")
		)
		(fp_line
			(start 0.67945 0.3048)
			(end 0.120396 0.3048)
			(stroke
				(width 0.1)
				(type default)
			)
			(layer "F.Fab")
		)
		(fp_line
			(start 0.120396 0.3048)
			(end 0.120396 0.2794)
			(stroke
				(width 0.1)
				(type default)
			)
			(layer "F.Fab")
		)
		(fp_line
			(start -0.12065 0.3048)
			(end -0.67945 0.3048)
			(stroke
				(width 0.1)
				(type default)
			)
			(layer "F.Fab")
		)
		(fp_line
			(start -0.67945 0.3048)
			(end -0.67945 -0.305054)
			(stroke
				(width 0.1)
				(type default)
			)
			(layer "F.Fab")
		)
		(pad "1" smd circle
			(at -0.40005 0 90)
			(size 0 0)
			(layers "F.Cu" "F.Mask" "F.Paste")
			(net "P12V_SSD2")
		)
		(pad "2" smd circle
			(at 0.40005 0 90)
			(size 0 0)
			(layers "F.Cu" "F.Mask" "F.Paste")
			(net "P12V_SSD2_VIN_N")
		)
	)
	(footprint ""
		(layer "F.Cu")
		(at 205.822296 -212.577426 180)
		(property "Reference" "R5918"
			(at 0 0 180)
			(layer "F.SilkS")
			(hide yes)
			(effects
				(font
					(size 1.27 1.27)
				)
			)
		)
		(property "Value" ""
			(at 0 0 180)
			(layer "F.Fab")
			(effects
				(font
					(size 1.27 1.27)
				)
			)
		)
		(duplicate_pad_numbers_are_jumpers no)
		(fp_line
			(start 0.7874 0.4064)
			(end -0.7874 0.4064)
			(stroke
				(width 0.1524)
				(type default)
			)
			(layer "F.SilkS")
		)
		(fp_line
			(start 0.7874 -0.4064)
			(end 0.7874 0.4064)
			(stroke
				(width 0.1524)
				(type default)
			)
			(layer "F.SilkS")
		)
		(fp_line
			(start -0.7874 0.4064)
			(end -0.7874 -0.4064)
			(stroke
				(width 0.1524)
				(type default)
			)
			(layer "F.SilkS")
		)
		(fp_line
			(start -0.7874 -0.4064)
			(end 0.7874 -0.4064)
			(stroke
				(width 0.1524)
				(type default)
			)
			(layer "F.SilkS")
		)
		(fp_line
			(start 0.67945 0.3048)
			(end 0.120396 0.3048)
			(stroke
				(width 0.1)
				(type default)
			)
			(layer "F.Fab")
		)
		(fp_line
			(start 0.67945 -0.3048)
			(end 0.67945 0.3048)
			(stroke
				(width 0.1)
				(type default)
			)
			(layer "F.Fab")
		)
		(fp_line
			(start 0.12065 -0.2794)
			(end 0.12065 -0.3048)
			(stroke
				(width 0.1)
				(type default)
			)
			(layer "F.Fab")
		)
		(fp_line
			(start 0.12065 -0.3048)
			(end 0.67945 -0.3048)
			(stroke
				(width 0.1)
				(type default)
			)
			(layer "F.Fab")
		)
		(fp_line
			(start 0.120396 0.3048)
			(end 0.120396 0.2794)
			(stroke
				(width 0.1)
				(type default)
			)
			(layer "F.Fab")
		)
		(fp_line
			(start 0.120396 0.2794)
			(end -0.12065 0.2794)
			(stroke
				(width 0.1)
				(type default)
			)
			(layer "F.Fab")
		)
		(fp_line
			(start -0.12065 0.3048)
			(end -0.67945 0.3048)
			(stroke
				(width 0.1)
				(type default)
			)
			(layer "F.Fab")
		)
		(fp_line
			(start -0.12065 0.2794)
			(end -0.12065 0.3048)
			(stroke
				(width 0.1)
				(type default)
			)
			(layer "F.Fab")
		)
		(fp_line
			(start -0.12065 -0.2794)
			(end 0.12065 -0.2794)
			(stroke
				(width 0.1)
				(type default)
			)
			(layer "F.Fab")
		)
		(fp_line
			(start -0.12065 -0.305054)
			(end -0.12065 -0.2794)
			(stroke
				(width 0.1)
				(type default)
			)
			(layer "F.Fab")
		)
		(fp_line
			(start -0.67945 0.3048)
			(end -0.67945 -0.305054)
			(stroke
				(width 0.1)
				(type default)
			)
			(layer "F.Fab")
		)
		(fp_line
			(start -0.67945 -0.305054)
			(end -0.12065 -0.305054)
			(stroke
				(width 0.1)
				(type default)
			)
			(layer "F.Fab")
		)
		(pad "1" smd circle
			(at -0.40005 0 180)
			(size 0 0)
			(layers "F.Cu" "F.Mask" "F.Paste")
			(net "BIC_UART_SEL2")
		)
		(pad "2" smd circle
			(at 0.40005 0 180)
			(size 0 0)
			(layers "F.Cu" "F.Mask" "F.Paste")
			(net "P3V3_AUX")
		)
	)
	(footprint ""
		(layer "F.Cu")
		(at 45.738542 -44.341542 90)
		(property "Reference" "C206"
			(at 0 0 90)
			(layer "F.SilkS")
			(hide yes)
			(effects
				(font
					(size 1.27 1.27)
				)
			)
		)
		(property "Value" ""
			(at 0 0 90)
			(layer "F.Fab")
			(effects
				(font
					(size 1.27 1.27)
				)
			)
		)
		(duplicate_pad_numbers_are_jumpers no)
		(fp_line
			(start 0.7874 -0.4064)
			(end 0.7874 0.4064)
			(stroke
				(width 0.1524)
				(type default)
			)
			(layer "F.SilkS")
		)
		(fp_line
			(start -0.7874 -0.4064)
			(end 0.7874 -0.4064)
			(stroke
				(width 0.1524)
				(type default)
			)
			(layer "F.SilkS")
		)
		(fp_line
			(start 0.7874 0.4064)
			(end -0.7874 0.4064)
			(stroke
				(width 0.1524)
				(type default)
			)
			(layer "F.SilkS")
		)
		(fp_line
			(start -0.7874 0.4064)
			(end -0.7874 -0.4064)
			(stroke
				(width 0.1524)
				(type default)
			)
			(layer "F.SilkS")
		)
		(fp_line
			(start -0.12065 -0.305054)
			(end -0.12065 -0.2794)
			(stroke
				(width 0.1)
				(type default)
			)
			(layer "F.Fab")
		)
		(fp_line
			(start -0.67945 -0.305054)
			(end -0.12065 -0.305054)
			(stroke
				(width 0.1)
				(type default)
			)
			(layer "F.Fab")
		)
		(fp_line
			(start 0.67945 -0.3048)
			(end 0.67945 0.3048)
			(stroke
				(width 0.1)
				(type default)
			)
			(layer "F.Fab")
		)
		(fp_line
			(start 0.12065 -0.3048)
			(end 0.67945 -0.3048)
			(stroke
				(width 0.1)
				(type default)
			)
			(layer "F.Fab")
		)
		(fp_line
			(start 0.12065 -0.2794)
			(end 0.12065 -0.3048)
			(stroke
				(width 0.1)
				(type default)
			)
			(layer "F.Fab")
		)
		(fp_line
			(start -0.12065 -0.2794)
			(end 0.12065 -0.2794)
			(stroke
				(width 0.1)
				(type default)
			)
			(layer "F.Fab")
		)
		(fp_line
			(start 0.120396 0.2794)
			(end -0.12065 0.2794)
			(stroke
				(width 0.1)
				(type default)
			)
			(layer "F.Fab")
		)
		(fp_line
			(start -0.12065 0.2794)
			(end -0.12065 0.3048)
			(stroke
				(width 0.1)
				(type default)
			)
			(layer "F.Fab")
		)
		(fp_line
			(start 0.67945 0.3048)
			(end 0.120396 0.3048)
			(stroke
				(width 0.1)
				(type default)
			)
			(layer "F.Fab")
		)
		(fp_line
			(start 0.120396 0.3048)
			(end 0.120396 0.2794)
			(stroke
				(width 0.1)
				(type default)
			)
			(layer "F.Fab")
		)
		(fp_line
			(start -0.12065 0.3048)
			(end -0.67945 0.3048)
			(stroke
				(width 0.1)
				(type default)
			)
			(layer "F.Fab")
		)
		(fp_line
			(start -0.67945 0.3048)
			(end -0.67945 -0.305054)
			(stroke
				(width 0.1)
				(type default)
			)
			(layer "F.Fab")
		)
		(pad "1" smd circle
			(at -0.40005 0 90)
			(size 0 0)
			(layers "F.Cu" "F.Mask" "F.Paste")
			(net "P12V_SSD1_VIN_P")
		)
		(pad "2" smd circle
			(at 0.40005 0 90)
			(size 0 0)
			(layers "F.Cu" "F.Mask" "F.Paste")
			(net "P12V_SSD1_VIN_N")
		)
	)
	(footprint ""
		(layer "F.Cu")
		(at 111.836708 -343.952322 90)
		(property "Reference" "C340"
			(at 0 0 90)
			(layer "F.SilkS")
			(hide yes)
			(effects
				(font
					(size 1.27 1.27)
				)
			)
		)
		(property "Value" ""
			(at 0 0 90)
			(layer "F.Fab")
			(effects
				(font
					(size 1.27 1.27)
				)
			)
		)
		(duplicate_pad_numbers_are_jumpers no)
		(fp_line
			(start 0.299974 -0.150114)
			(end 0.299974 0.150114)
			(stroke
				(width 0.1)
				(type default)
			)
			(layer "F.Fab")
		)
		(fp_line
			(start -0.299974 -0.150114)
			(end 0.299974 -0.150114)
			(stroke
				(width 0.1)
				(type default)
			)
			(layer "F.Fab")
		)
		(fp_line
			(start 0.299974 0.150114)
			(end -0.299974 0.150114)
			(stroke
				(width 0.1)
				(type default)
			)
			(layer "F.Fab")
		)
		(fp_line
			(start -0.299974 0.150114)
			(end -0.299974 -0.150114)
			(stroke
				(width 0.1)
				(type default)
			)
			(layer "F.Fab")
		)
		(pad "1" smd rect
			(at -0.2667 0 90)
			(size 0.3048 0.381)
			(layers "F.Cu" "F.Mask" "F.Paste")
			(net "P5E_PEX1_STN6_TX_DP<111>")
		)
		(pad "2" smd rect
			(at 0.2667 0 90)
			(size 0.3048 0.381)
			(layers "F.Cu" "F.Mask" "F.Paste")
			(net "P5E_PEX1_STN6_TX_C_DP<111>")
		)
	)
	(footprint ""
		(layer "F.Cu")
		(at 28.04922 -287.395412 -90)
		(property "Reference" "C3052"
			(at 0 0 270)
			(layer "F.SilkS")
			(hide yes)
			(effects
				(font
					(size 1.27 1.27)
				)
			)
		)
		(property "Value" ""
			(at 0 0 270)
			(layer "F.Fab")
			(effects
				(font
					(size 1.27 1.27)
				)
			)
		)
		(duplicate_pad_numbers_are_jumpers no)
		(fp_line
			(start -0.299974 0.150114)
			(end -0.299974 -0.150114)
			(stroke
				(width 0.1)
				(type default)
			)
			(layer "F.Fab")
		)
		(fp_line
			(start 0.299974 0.150114)
			(end -0.299974 0.150114)
			(stroke
				(width 0.1)
				(type default)
			)
			(layer "F.Fab")
		)
		(fp_line
			(start -0.299974 -0.150114)
			(end 0.299974 -0.150114)
			(stroke
				(width 0.1)
				(type default)
			)
			(layer "F.Fab")
		)
		(fp_line
			(start 0.299974 -0.150114)
			(end 0.299974 0.150114)
			(stroke
				(width 0.1)
				(type default)
			)
			(layer "F.Fab")
		)
		(pad "1" smd rect
			(at -0.2667 0 270)
			(size 0.3048 0.381)
			(layers "F.Cu" "F.Mask" "F.Paste")
			(net "P1V8_PLL0_PEX0")
		)
		(pad "2" smd rect
			(at 0.2667 0 270)
			(size 0.3048 0.381)
			(layers "F.Cu" "F.Mask" "F.Paste")
			(net "GND")
		)
	)
	(footprint ""
		(layer "F.Cu")
		(at 353.015296 -59.546236 90)
		(property "Reference" "C2894"
			(at 0 0 90)
			(layer "F.SilkS")
			(hide yes)
			(effects
				(font
					(size 1.27 1.27)
				)
			)
		)
		(property "Value" ""
			(at 0 0 90)
			(layer "F.Fab")
			(effects
				(font
					(size 1.27 1.27)
				)
			)
		)
		(duplicate_pad_numbers_are_jumpers no)
		(fp_line
			(start 0.7874 -0.4064)
			(end 0.7874 0.4064)
			(stroke
				(width 0.1524)
				(type default)
			)
			(layer "F.SilkS")
		)
		(fp_line
			(start -0.7874 -0.4064)
			(end 0.7874 -0.4064)
			(stroke
				(width 0.1524)
				(type default)
			)
			(layer "F.SilkS")
		)
		(fp_line
			(start 0.7874 0.4064)
			(end -0.7874 0.4064)
			(stroke
				(width 0.1524)
				(type default)
			)
			(layer "F.SilkS")
		)
		(fp_line
			(start -0.7874 0.4064)
			(end -0.7874 -0.4064)
			(stroke
				(width 0.1524)
				(type default)
			)
			(layer "F.SilkS")
		)
		(fp_line
			(start -0.12065 -0.305054)
			(end -0.12065 -0.2794)
			(stroke
				(width 0.1)
				(type default)
			)
			(layer "F.Fab")
		)
		(fp_line
			(start -0.67945 -0.305054)
			(end -0.12065 -0.305054)
			(stroke
				(width 0.1)
				(type default)
			)
			(layer "F.Fab")
		)
		(fp_line
			(start 0.67945 -0.3048)
			(end 0.67945 0.3048)
			(stroke
				(width 0.1)
				(type default)
			)
			(layer "F.Fab")
		)
		(fp_line
			(start 0.12065 -0.3048)
			(end 0.67945 -0.3048)
			(stroke
				(width 0.1)
				(type default)
			)
			(layer "F.Fab")
		)
		(fp_line
			(start 0.12065 -0.2794)
			(end 0.12065 -0.3048)
			(stroke
				(width 0.1)
				(type default)
			)
			(layer "F.Fab")
		)
		(fp_line
			(start -0.12065 -0.2794)
			(end 0.12065 -0.2794)
			(stroke
				(width 0.1)
				(type default)
			)
			(layer "F.Fab")
		)
		(fp_line
			(start 0.120396 0.2794)
			(end -0.12065 0.2794)
			(stroke
				(width 0.1)
				(type default)
			)
			(layer "F.Fab")
		)
		(fp_line
			(start -0.12065 0.2794)
			(end -0.12065 0.3048)
			(stroke
				(width 0.1)
				(type default)
			)
			(layer "F.Fab")
		)
		(fp_line
			(start 0.67945 0.3048)
			(end 0.120396 0.3048)
			(stroke
				(width 0.1)
				(type default)
			)
			(layer "F.Fab")
		)
		(fp_line
			(start 0.120396 0.3048)
			(end 0.120396 0.2794)
			(stroke
				(width 0.1)
				(type default)
			)
			(layer "F.Fab")
		)
		(fp_line
			(start -0.12065 0.3048)
			(end -0.67945 0.3048)
			(stroke
				(width 0.1)
				(type default)
			)
			(layer "F.Fab")
		)
		(fp_line
			(start -0.67945 0.3048)
			(end -0.67945 -0.305054)
			(stroke
				(width 0.1)
				(type default)
			)
			(layer "F.Fab")
		)
		(pad "1" smd circle
			(at -0.40005 0 90)
			(size 0 0)
			(layers "F.Cu" "F.Mask" "F.Paste")
			(net "SSD12_AUX_P3V3_EN_R")
		)
		(pad "2" smd circle
			(at 0.40005 0 90)
			(size 0 0)
			(layers "F.Cu" "F.Mask" "F.Paste")
			(net "GND")
		)
	)
)
